(kicad_pcb
	(version 20241229)
	(generator "pcbnew")
	(generator_version "9.0")
	(general
		(thickness 1.61)
		(legacy_teardrops no)
	)
	(paper "A3")
	(title_block
		(title "RDIMM DDR5 Tester")
		(date "2026-05-21")
		(rev "2.2.0")
		(company "Antmicro")
		(comment 9 "footprints 479-483 of 796")
	)
	(layers
		(0 "F.Cu" signal)
		(4 "In1.Cu" power)
		(6 "In2.Cu" mixed)
		(8 "In3.Cu" power)
		(10 "In4.Cu" mixed)
		(12 "In5.Cu" power)
		(14 "In6.Cu" mixed)
		(16 "In7.Cu" power)
		(18 "In8.Cu" power)
		(20 "In9.Cu" mixed)
		(22 "In10.Cu" power)
		(2 "B.Cu" signal)
		(9 "F.Adhes" user "F.Adhesive")
		(11 "B.Adhes" user "B.Adhesive")
		(13 "F.Paste" user)
		(15 "B.Paste" user)
		(5 "F.SilkS" user "F.Silkscreen")
		(7 "B.SilkS" user "B.Silkscreen")
		(1 "F.Mask" user)
		(3 "B.Mask" user)
		(17 "Dwgs.User" user "User.Drawings")
		(19 "Cmts.User" user "User.Comments")
		(21 "Eco1.User" user "User.Eco1")
		(23 "Eco2.User" user "User.Eco2")
		(25 "Edge.Cuts" user)
		(27 "Margin" user)
		(31 "F.CrtYd" user "F.Courtyard")
		(29 "B.CrtYd" user "B.Courtyard")
		(35 "F.Fab" user)
		(33 "B.Fab" user)
	)
	(footprint "antmicro-footprints:C_0402_1005Metric_EIA"
		(layer "B.Cu")
		(at 196 140.5 -90)
		(descr "Capacitor SMD 0402 (1005 Metric), square (rectangular) end terminal, IPC_7351 nominal, (Body size source: IPC-SM-782 page 76, https://www.pcb-3d.com/wordpress/wp-content/uploads/ipc-sm-782a_amendment_1_and_2.pdf)")
		(tags "capacitor 0402")
		(property "Reference" "C74"
			(at -1.175 -1.475 90)
			(layer "B.SilkS")
			(effects
				(font
					(size 0.7 0.7)
					(thickness 0.15)
				)
				(justify left bottom mirror)
			)
		)
		(property "Value" "C_100n_0402"
			(at 0 -1.169 90)
			(layer "B.Fab")
			(effects
				(font
					(size 0.7 0.7)
					(thickness 0.15)
				)
				(justify left bottom mirror)
			)
		)
		(property "Datasheet" "https://www.murata.com/products/productdetail?partno=GRM155R61H104KE14%23"
			(at 0 0 270)
			(layer "F.Fab")
			(hide yes)
			(effects
				(font
					(size 1.27 1.27)
					(thickness 0.15)
				)
			)
		)
		(property "MPN" "GRM155R61H104KE14D"
			(at 0 0 270)
			(unlocked yes)
			(layer "B.Fab")
			(hide yes)
			(effects
				(font
					(size 1 1)
					(thickness 0.15)
				)
				(justify mirror)
			)
		)
		(property "Manufacturer" "Murata"
			(at 0 0 270)
			(unlocked yes)
			(layer "B.Fab")
			(hide yes)
			(effects
				(font
					(size 1 1)
					(thickness 0.15)
				)
				(justify mirror)
			)
		)
		(property "License" "Apache-2.0"
			(at 0 0 270)
			(unlocked yes)
			(layer "B.Fab")
			(hide yes)
			(effects
				(font
					(size 1 1)
					(thickness 0.15)
				)
				(justify mirror)
			)
		)
		(property "Author" "Antmicro"
			(at 0 0 270)
			(unlocked yes)
			(layer "B.Fab")
			(hide yes)
			(effects
				(font
					(size 1 1)
					(thickness 0.15)
				)
				(justify mirror)
			)
		)
		(property "Val" "100n"
			(at 0 0 270)
			(unlocked yes)
			(layer "B.Fab")
			(hide yes)
			(effects
				(font
					(size 1 1)
					(thickness 0.15)
				)
				(justify mirror)
			)
		)
		(property "Voltage" "50V"
			(at 0 0 270)
			(unlocked yes)
			(layer "B.Fab")
			(hide yes)
			(effects
				(font
					(size 1 1)
					(thickness 0.15)
				)
				(justify mirror)
			)
		)
		(property "Dielectric" "X5R"
			(at 0 0 270)
			(unlocked yes)
			(layer "B.Fab")
			(hide yes)
			(effects
				(font
					(size 1 1)
					(thickness 0.15)
				)
				(justify mirror)
			)
		)
		(sheetname "/FPGA power/")
		(sheetfile "fpga-power.kicad_sch")
		(attr smd)
		(fp_rect
			(start -0.95 0.45)
			(end 0.95 -0.45)
			(stroke
				(width 0.05)
				(type default)
			)
			(fill no)
			(layer "B.CrtYd")
		)
		(fp_line
			(start -0.5 0.25)
			(end 0.498 0.25)
			(stroke
				(width 0.15)
				(type solid)
			)
			(layer "B.Fab")
		)
		(fp_line
			(start 0.498 0.25)
			(end 0.498 -0.248)
			(stroke
				(width 0.15)
				(type solid)
			)
			(layer "B.Fab")
		)
		(fp_line
			(start -0.5 -0.248)
			(end -0.5 0.25)
			(stroke
				(width 0.15)
				(type solid)
			)
			(layer "B.Fab")
		)
		(fp_line
			(start 0.498 -0.248)
			(end -0.5 -0.248)
			(stroke
				(width 0.15)
				(type solid)
			)
			(layer "B.Fab")
		)
		(fp_text user "License: Apache-2.0"
			(at -0.9656 -4.369 90)
			(layer "B.Fab")
			(effects
				(font
					(size 0.7 0.7)
					(thickness 0.15)
				)
				(justify left bottom mirror)
			)
		)
		(fp_text user "Author: Antmicro"
			(at -0.9656 -5.569 90)
			(layer "B.Fab")
			(effects
				(font
					(size 0.7 0.7)
					(thickness 0.15)
				)
				(justify left bottom mirror)
			)
		)
		(fp_text user "${REFERENCE}"
			(at -0.9656 -3.169 90)
			(layer "B.Fab")
			(effects
				(font
					(size 0.7 0.7)
					(thickness 0.15)
				)
				(justify left bottom mirror)
			)
		)
		(pad "1" smd roundrect
			(at -0.5 0 180)
			(size 0.6 0.6)
			(layers "B.Cu" "B.Mask" "B.Paste")
			(roundrect_rratio 0.25)
			(net 1 "GND")
			(pintype "passive")
		)
		(pad "2" smd roundrect
			(at 0.498 0 270)
			(size 0.6 0.6)
			(layers "B.Cu" "B.Mask" "B.Paste")
			(roundrect_rratio 0.25)
			(net 687 "VDDQ")
			(pintype "passive")
		)
	)
	(footprint "antmicro-footprints:R_0402_1005Metric"
		(layer "B.Cu")
		(at 238.451999 164.2)
		(descr "Resistor SMD 0402")
		(tags "resistor SMD 0402")
		(property "Reference" "R137"
			(at 1.173001 0.475 0)
			(layer "B.SilkS")
			(effects
				(font
					(size 0.7 0.7)
					(thickness 0.15)
				)
				(justify right bottom mirror)
			)
		)
		(property "Value" "R_0R_0402"
			(at -1.011843 -1.772047 0)
			(layer "B.Fab")
			(effects
				(font
					(size 0.7 0.7)
					(thickness 0.15)
				)
				(justify right bottom mirror)
			)
		)
		(property "Datasheet" "https://industrial.panasonic.com/cdbs/www-data/pdf/RDA0000/AOA0000C301.pdf"
			(at 0 0 0)
			(layer "F.Fab")
			(hide yes)
			(effects
				(font
					(size 1.27 1.27)
					(thickness 0.15)
				)
			)
		)
		(property "MPN" "ERJ2GE0R00X"
			(at 0 0 0)
			(unlocked yes)
			(layer "B.Fab")
			(hide yes)
			(effects
				(font
					(size 1 1)
					(thickness 0.15)
				)
				(justify mirror)
			)
		)
		(property "Manufacturer" "Panasonic"
			(at 0 0 0)
			(unlocked yes)
			(layer "B.Fab")
			(hide yes)
			(effects
				(font
					(size 1 1)
					(thickness 0.15)
				)
				(justify mirror)
			)
		)
		(property "License" "Apache-2.0"
			(at 0 0 0)
			(unlocked yes)
			(layer "B.Fab")
			(hide yes)
			(effects
				(font
					(size 1 1)
					(thickness 0.15)
				)
				(justify mirror)
			)
		)
		(property "Author" "Antmicro"
			(at 0 0 0)
			(unlocked yes)
			(layer "B.Fab")
			(hide yes)
			(effects
				(font
					(size 1 1)
					(thickness 0.15)
				)
				(justify mirror)
			)
		)
		(property "Val" "0R"
			(at 0 0 0)
			(unlocked yes)
			(layer "B.Fab")
			(hide yes)
			(effects
				(font
					(size 1 1)
					(thickness 0.15)
				)
				(justify mirror)
			)
		)
		(property "Tolerance" "~"
			(at 0 0 0)
			(unlocked yes)
			(layer "B.Fab")
			(hide yes)
			(effects
				(font
					(size 1 1)
					(thickness 0.15)
				)
				(justify mirror)
			)
		)
		(property "Current" "1A"
			(at 0 0 0)
			(unlocked yes)
			(layer "B.Fab")
			(hide yes)
			(effects
				(font
					(size 1 1)
					(thickness 0.15)
				)
				(justify mirror)
			)
		)
		(sheetname "/Supply/")
		(sheetfile "supply.kicad_sch")
		(attr smd)
		(fp_rect
			(start -0.925 0.47)
			(end 0.925 -0.47)
			(stroke
				(width 0.05)
				(type default)
			)
			(fill no)
			(layer "B.CrtYd")
		)
		(fp_rect
			(start -0.5 0.25)
			(end 0.5 -0.25)
			(stroke
				(width 0.15)
				(type solid)
			)
			(fill no)
			(layer "B.Fab")
		)
		(fp_text user "${REFERENCE}"
			(at -0.95 -3.168 180)
			(layer "B.Fab")
			(effects
				(font
					(size 0.7 0.7)
					(thickness 0.15)
				)
				(justify left bottom mirror)
			)
		)
		(fp_text user "License: Apache-2.0"
			(at -0.95 -5.169 180)
			(layer "B.Fab")
			(effects
				(font
					(size 0.7 0.7)
					(thickness 0.15)
				)
				(justify left bottom mirror)
			)
		)
		(fp_text user "Author: Antmicro"
			(at -0.95 -4.169 180)
			(layer "B.Fab")
			(effects
				(font
					(size 0.7 0.7)
					(thickness 0.15)
				)
				(justify left bottom mirror)
			)
		)
		(pad "1" smd roundrect
			(at -0.48 0)
			(size 0.59 0.64)
			(layers "B.Cu" "B.Mask" "B.Paste")
			(roundrect_rratio 0.25)
			(net 183 "POWER")
			(pintype "passive")
		)
		(pad "2" smd roundrect
			(at 0.48 0)
			(size 0.59 0.64)
			(layers "B.Cu" "B.Mask" "B.Paste")
			(roundrect_rratio 0.25)
			(net 484 "PG2")
			(pintype "passive")
		)
	)
	(footprint "antmicro-footprints:C_0402_1005Metric_EIA"
		(layer "B.Cu")
		(at 185 148.5 -90)
		(descr "Capacitor SMD 0402 (1005 Metric), square (rectangular) end terminal, IPC_7351 nominal, (Body size source: IPC-SM-782 page 76, https://www.pcb-3d.com/wordpress/wp-content/uploads/ipc-sm-782a_amendment_1_and_2.pdf)")
		(tags "capacitor 0402")
		(property "Reference" "C35"
			(at -11.7 30.625 90)
			(layer "B.SilkS")
			(effects
				(font
					(size 0.7 0.7)
					(thickness 0.15)
				)
				(justify left bottom mirror)
			)
		)
		(property "Value" "C_1u_25V_0402"
			(at 0 -1.169 90)
			(layer "B.Fab")
			(effects
				(font
					(size 0.7 0.7)
					(thickness 0.15)
				)
				(justify left bottom mirror)
			)
		)
		(property "Datasheet" "https://www.murata.com/products/productdetail?partno=GRM155R61E105KE11%23"
			(at 0 0 270)
			(layer "F.Fab")
			(hide yes)
			(effects
				(font
					(size 1.27 1.27)
					(thickness 0.15)
				)
			)
		)
		(property "MPN" "GRM155R61E105KE11J"
			(at 0 0 270)
			(unlocked yes)
			(layer "B.Fab")
			(hide yes)
			(effects
				(font
					(size 1 1)
					(thickness 0.15)
				)
				(justify mirror)
			)
		)
		(property "Manufacturer" "Murata"
			(at 0 0 270)
			(unlocked yes)
			(layer "B.Fab")
			(hide yes)
			(effects
				(font
					(size 1 1)
					(thickness 0.15)
				)
				(justify mirror)
			)
		)
		(property "License" "Apache-2.0"
			(at 0 0 270)
			(unlocked yes)
			(layer "B.Fab")
			(hide yes)
			(effects
				(font
					(size 1 1)
					(thickness 0.15)
				)
				(justify mirror)
			)
		)
		(property "Author" "Antmicro"
			(at 0 0 270)
			(unlocked yes)
			(layer "B.Fab")
			(hide yes)
			(effects
				(font
					(size 1 1)
					(thickness 0.15)
				)
				(justify mirror)
			)
		)
		(property "Val" "1u"
			(at 0 0 270)
			(unlocked yes)
			(layer "B.Fab")
			(hide yes)
			(effects
				(font
					(size 1 1)
					(thickness 0.15)
				)
				(justify mirror)
			)
		)
		(property "Voltage" "25V"
			(at 0 0 270)
			(unlocked yes)
			(layer "B.Fab")
			(hide yes)
			(effects
				(font
					(size 1 1)
					(thickness 0.15)
				)
				(justify mirror)
			)
		)
		(property "Dielectric" "X5R"
			(at 0 0 270)
			(unlocked yes)
			(layer "B.Fab")
			(hide yes)
			(effects
				(font
					(size 1 1)
					(thickness 0.15)
				)
				(justify mirror)
			)
		)
		(sheetname "/FPGA power/")
		(sheetfile "fpga-power.kicad_sch")
		(attr smd)
		(fp_rect
			(start -0.95 0.45)
			(end 0.95 -0.45)
			(stroke
				(width 0.05)
				(type default)
			)
			(fill no)
			(layer "B.CrtYd")
		)
		(fp_line
			(start -0.5 0.25)
			(end 0.498 0.25)
			(stroke
				(width 0.15)
				(type solid)
			)
			(layer "B.Fab")
		)
		(fp_line
			(start 0.498 0.25)
			(end 0.498 -0.248)
			(stroke
				(width 0.15)
				(type solid)
			)
			(layer "B.Fab")
		)
		(fp_line
			(start -0.5 -0.248)
			(end -0.5 0.25)
			(stroke
				(width 0.15)
				(type solid)
			)
			(layer "B.Fab")
		)
		(fp_line
			(start 0.498 -0.248)
			(end -0.5 -0.248)
			(stroke
				(width 0.15)
				(type solid)
			)
			(layer "B.Fab")
		)
		(fp_text user "Author: Antmicro"
			(at -0.9656 -5.569 90)
			(layer "B.Fab")
			(effects
				(font
					(size 0.7 0.7)
					(thickness 0.15)
				)
				(justify left bottom mirror)
			)
		)
		(fp_text user "License: Apache-2.0"
			(at -0.9656 -4.369 90)
			(layer "B.Fab")
			(effects
				(font
					(size 0.7 0.7)
					(thickness 0.15)
				)
				(justify left bottom mirror)
			)
		)
		(fp_text user "${REFERENCE}"
			(at -0.9656 -3.169 90)
			(layer "B.Fab")
			(effects
				(font
					(size 0.7 0.7)
					(thickness 0.15)
				)
				(justify left bottom mirror)
			)
		)
		(pad "1" smd roundrect
			(at -0.5 0 180)
			(size 0.6 0.6)
			(layers "B.Cu" "B.Mask" "B.Paste")
			(roundrect_rratio 0.25)
			(net 1 "GND")
			(pintype "passive")
		)
		(pad "2" smd roundrect
			(at 0.498 0 270)
			(size 0.6 0.6)
			(layers "B.Cu" "B.Mask" "B.Paste")
			(roundrect_rratio 0.25)
			(net 553 "+0V85")
			(pintype "passive")
		)
	)
	(footprint "antmicro-footprints:C_0402_1005Metric_EIA"
		(layer "B.Cu")
		(at 190 158.5 90)
		(descr "Capacitor SMD 0402 (1005 Metric), square (rectangular) end terminal, IPC_7351 nominal, (Body size source: IPC-SM-782 page 76, https://www.pcb-3d.com/wordpress/wp-content/uploads/ipc-sm-782a_amendment_1_and_2.pdf)")
		(tags "capacitor 0402")
		(property "Reference" "C61"
			(at 9.525 -30.65 90)
			(layer "B.SilkS")
			(effects
				(font
					(size 0.7 0.7)
					(thickness 0.15)
				)
				(justify right bottom mirror)
			)
		)
		(property "Value" "C_100n_0402"
			(at 0 -1.169 90)
			(layer "B.Fab")
			(effects
				(font
					(size 0.7 0.7)
					(thickness 0.15)
				)
				(justify right bottom mirror)
			)
		)
		(property "Datasheet" "https://www.murata.com/products/productdetail?partno=GRM155R61H104KE14%23"
			(at 0 0 90)
			(layer "F.Fab")
			(hide yes)
			(effects
				(font
					(size 1.27 1.27)
					(thickness 0.15)
				)
			)
		)
		(property "MPN" "GRM155R61H104KE14D"
			(at 0 0 90)
			(unlocked yes)
			(layer "B.Fab")
			(hide yes)
			(effects
				(font
					(size 1 1)
					(thickness 0.15)
				)
				(justify mirror)
			)
		)
		(property "Manufacturer" "Murata"
			(at 0 0 90)
			(unlocked yes)
			(layer "B.Fab")
			(hide yes)
			(effects
				(font
					(size 1 1)
					(thickness 0.15)
				)
				(justify mirror)
			)
		)
		(property "License" "Apache-2.0"
			(at 0 0 90)
			(unlocked yes)
			(layer "B.Fab")
			(hide yes)
			(effects
				(font
					(size 1 1)
					(thickness 0.15)
				)
				(justify mirror)
			)
		)
		(property "Author" "Antmicro"
			(at 0 0 90)
			(unlocked yes)
			(layer "B.Fab")
			(hide yes)
			(effects
				(font
					(size 1 1)
					(thickness 0.15)
				)
				(justify mirror)
			)
		)
		(property "Val" "100n"
			(at 0 0 90)
			(unlocked yes)
			(layer "B.Fab")
			(hide yes)
			(effects
				(font
					(size 1 1)
					(thickness 0.15)
				)
				(justify mirror)
			)
		)
		(property "Voltage" "50V"
			(at 0 0 90)
			(unlocked yes)
			(layer "B.Fab")
			(hide yes)
			(effects
				(font
					(size 1 1)
					(thickness 0.15)
				)
				(justify mirror)
			)
		)
		(property "Dielectric" "X5R"
			(at 0 0 90)
			(unlocked yes)
			(layer "B.Fab")
			(hide yes)
			(effects
				(font
					(size 1 1)
					(thickness 0.15)
				)
				(justify mirror)
			)
		)
		(sheetname "/FPGA power/")
		(sheetfile "fpga-power.kicad_sch")
		(attr smd)
		(fp_rect
			(start -0.95 0.45)
			(end 0.95 -0.45)
			(stroke
				(width 0.05)
				(type default)
			)
			(fill no)
			(layer "B.CrtYd")
		)
		(fp_line
			(start 0.498 -0.248)
			(end -0.5 -0.248)
			(stroke
				(width 0.15)
				(type solid)
			)
			(layer "B.Fab")
		)
		(fp_line
			(start -0.5 -0.248)
			(end -0.5 0.25)
			(stroke
				(width 0.15)
				(type solid)
			)
			(layer "B.Fab")
		)
		(fp_line
			(start 0.498 0.25)
			(end 0.498 -0.248)
			(stroke
				(width 0.15)
				(type solid)
			)
			(layer "B.Fab")
		)
		(fp_line
			(start -0.5 0.25)
			(end 0.498 0.25)
			(stroke
				(width 0.15)
				(type solid)
			)
			(layer "B.Fab")
		)
		(fp_text user "${REFERENCE}"
			(at -0.9656 -3.169 270)
			(layer "B.Fab")
			(effects
				(font
					(size 0.7 0.7)
					(thickness 0.15)
				)
				(justify left bottom mirror)
			)
		)
		(fp_text user "License: Apache-2.0"
			(at -0.9656 -4.369 270)
			(layer "B.Fab")
			(effects
				(font
					(size 0.7 0.7)
					(thickness 0.15)
				)
				(justify left bottom mirror)
			)
		)
		(fp_text user "Author: Antmicro"
			(at -0.9656 -5.569 270)
			(layer "B.Fab")
			(effects
				(font
					(size 0.7 0.7)
					(thickness 0.15)
				)
				(justify left bottom mirror)
			)
		)
		(pad "1" smd roundrect
			(at -0.5 0)
			(size 0.6 0.6)
			(layers "B.Cu" "B.Mask" "B.Paste")
			(roundrect_rratio 0.25)
			(net 1 "GND")
			(pintype "passive")
		)
		(pad "2" smd roundrect
			(at 0.498 0 90)
			(size 0.6 0.6)
			(layers "B.Cu" "B.Mask" "B.Paste")
			(roundrect_rratio 0.25)
			(net 553 "+0V85")
			(pintype "passive")
		)
	)
	(footprint "antmicro-footprints:C_0402_1005Metric_EIA"
		(layer "B.Cu")
		(at 191 162.5 -90)
		(descr "Capacitor SMD 0402 (1005 Metric), square (rectangular) end terminal, IPC_7351 nominal, (Body size source: IPC-SM-782 page 76, https://www.pcb-3d.com/wordpress/wp-content/uploads/ipc-sm-782a_amendment_1_and_2.pdf)")
		(tags "capacitor 0402")
		(property "Reference" "C103"
			(at 1.1 -0.2 90)
			(layer "B.SilkS")
			(effects
				(font
					(size 0.7 0.7)
					(thickness 0.15)
				)
				(justify left bottom mirror)
			)
		)
		(property "Value" "C_4u7_0402"
			(at 0 -1.169 90)
			(layer "B.Fab")
			(effects
				(font
					(size 0.7 0.7)
					(thickness 0.15)
				)
				(justify left bottom mirror)
			)
		)
		(property "Datasheet" "https://www.murata.com/products/productdetail?partno=GRM155R61A475MEAA%23"
			(at 0 0 270)
			(layer "F.Fab")
			(hide yes)
			(effects
				(font
					(size 1.27 1.27)
					(thickness 0.15)
				)
			)
		)
		(property "Manufacturer" "Murata"
			(at 0 0 270)
			(unlocked yes)
			(layer "B.Fab")
			(hide yes)
			(effects
				(font
					(size 1 1)
					(thickness 0.15)
				)
				(justify mirror)
			)
		)
		(property "MPN" "GRM155R61A475MEAAD"
			(at 0 0 270)
			(unlocked yes)
			(layer "B.Fab")
			(hide yes)
			(effects
				(font
					(size 1 1)
					(thickness 0.15)
				)
				(justify mirror)
			)
		)
		(property "Val" "4u7"
			(at 0 0 270)
			(unlocked yes)
			(layer "B.Fab")
			(hide yes)
			(effects
				(font
					(size 1 1)
					(thickness 0.15)
				)
				(justify mirror)
			)
		)
		(property "License" "Apache-2.0"
			(at 0 0 270)
			(unlocked yes)
			(layer "B.Fab")
			(hide yes)
			(effects
				(font
					(size 1 1)
					(thickness 0.15)
				)
				(justify mirror)
			)
		)
		(property "Author" "Antmicro"
			(at 0 0 270)
			(unlocked yes)
			(layer "B.Fab")
			(hide yes)
			(effects
				(font
					(size 1 1)
					(thickness 0.15)
				)
				(justify mirror)
			)
		)
		(property "Voltage" ""
			(at 0 0 270)
			(unlocked yes)
			(layer "B.Fab")
			(hide yes)
			(effects
				(font
					(size 1 1)
					(thickness 0.15)
				)
				(justify mirror)
			)
		)
		(property "Dielectric" ""
			(at 0 0 270)
			(unlocked yes)
			(layer "B.Fab")
			(hide yes)
			(effects
				(font
					(size 1 1)
					(thickness 0.15)
				)
				(justify mirror)
			)
		)
		(sheetname "/FPGA power/")
		(sheetfile "fpga-power.kicad_sch")
		(attr smd)
		(fp_rect
			(start -0.95 0.45)
			(end 0.95 -0.45)
			(stroke
				(width 0.05)
				(type default)
			)
			(fill no)
			(layer "B.CrtYd")
		)
		(fp_line
			(start -0.5 0.25)
			(end 0.498 0.25)
			(stroke
				(width 0.15)
				(type solid)
			)
			(layer "B.Fab")
		)
		(fp_line
			(start 0.498 0.25)
			(end 0.498 -0.248)
			(stroke
				(width 0.15)
				(type solid)
			)
			(layer "B.Fab")
		)
		(fp_line
			(start -0.5 -0.248)
			(end -0.5 0.25)
			(stroke
				(width 0.15)
				(type solid)
			)
			(layer "B.Fab")
		)
		(fp_line
			(start 0.498 -0.248)
			(end -0.5 -0.248)
			(stroke
				(width 0.15)
				(type solid)
			)
			(layer "B.Fab")
		)
		(fp_text user "License: Apache-2.0"
			(at -0.9656 -4.369 90)
			(layer "B.Fab")
			(effects
				(font
					(size 0.7 0.7)
					(thickness 0.15)
				)
				(justify left bottom mirror)
			)
		)
		(fp_text user "${REFERENCE}"
			(at -0.9656 -3.169 90)
			(layer "B.Fab")
			(effects
				(font
					(size 0.7 0.7)
					(thickness 0.15)
				)
				(justify left bottom mirror)
			)
		)
		(fp_text user "Author: Antmicro"
			(at -0.9656 -5.569 90)
			(layer "B.Fab")
			(effects
				(font
					(size 0.7 0.7)
					(thickness 0.15)
				)
				(justify left bottom mirror)
			)
		)
		(pad "1" smd roundrect
			(at -0.5 0 180)
			(size 0.6 0.6)
			(layers "B.Cu" "B.Mask" "B.Paste")
			(roundrect_rratio 0.25)
			(net 172 "+1V2_MGTAVTT")
			(pintype "passive")
		)
		(pad "2" smd roundrect
			(at 0.498 0 270)
			(size 0.6 0.6)
			(layers "B.Cu" "B.Mask" "B.Paste")
			(roundrect_rratio 0.25)
			(net 1 "GND")
			(pintype "passive")
		)
	)
)
